(kicad_pcb
	(version 20241229)
	(generator "pcbnew")
	(generator_version "9.0")
	(general
		(thickness 1.62)
		(legacy_teardrops no)
	)
	(paper "A4")
	(title_block
		(title "OCuLink to 10GbE adapter")
		(date "2026-02-23")
		(rev "1.1.0")
		(company "Antmicro Ltd")
		(comment 1 "www.antmicro.com")
		(comment 9 "footprints 266-269 of 510")
	)
	(layers
		(0 "F.Cu" signal)
		(4 "In1.Cu" signal)
		(6 "In2.Cu" signal)
		(8 "In3.Cu" signal)
		(10 "In4.Cu" signal)
		(12 "In5.Cu" signal)
		(14 "In6.Cu" signal)
		(2 "B.Cu" signal)
		(9 "F.Adhes" user "F.Adhesive")
		(11 "B.Adhes" user "B.Adhesive")
		(13 "F.Paste" user)
		(15 "B.Paste" user)
		(5 "F.SilkS" user "F.Silkscreen")
		(7 "B.SilkS" user "B.Silkscreen")
		(1 "F.Mask" user)
		(3 "B.Mask" user)
		(17 "Dwgs.User" user "User.Drawings")
		(19 "Cmts.User" user "User.Comments")
		(21 "Eco1.User" user "User.Eco1")
		(23 "Eco2.User" user "User.Eco2")
		(25 "Edge.Cuts" user)
		(27 "Margin" user)
		(31 "F.CrtYd" user "F.Courtyard")
		(29 "B.CrtYd" user "B.Courtyard")
		(35 "F.Fab" user)
		(33 "B.Fab" user)
	)
	(footprint "antmicro-footprints:R_0402_1005Metric"
		(layer "F.Cu")
		(at 54.099998 92.849999 -90)
		(descr "Resistor SMD 0402")
		(tags "resistor SMD 0402")
		(property "Reference" "R32"
			(at -1.059999 3.019998 90)
			(layer "F.SilkS")
			(effects
				(font
					(size 0.7 0.7)
					(thickness 0.15)
				)
				(justify right top)
			)
		)
		(property "Value" "R_30k_0402"
			(at -1.011843 1.772046 90)
			(layer "F.Fab")
			(hide yes)
			(effects
				(font
					(size 0.7 0.7)
					(thickness 0.15)
				)
				(justify right top)
			)
		)
		(property "Datasheet" "https://www.bourns.com/docs/product-datasheets/cr.pdf"
			(at 0 0 90)
			(layer "F.Fab")
			(hide yes)
			(effects
				(font
					(size 1.27 1.27)
					(thickness 0.15)
				)
			)
		)
		(property "Description" "SMD Chip Resistor, 30 kohm, ± 1%, 63 mW, 0402 [1005 Metric], Thick Film, General Purpose"
			(at 0 0 90)
			(layer "F.Fab")
			(hide yes)
			(effects
				(font
					(size 1.27 1.27)
					(thickness 0.15)
				)
			)
		)
		(property "MPN" "CR0402-FX-3002GLF"
			(at 0 0 270)
			(unlocked yes)
			(layer "F.Fab")
			(hide yes)
			(effects
				(font
					(size 1 1)
					(thickness 0.15)
				)
			)
		)
		(property "Manufacturer" "Bourns"
			(at 0 0 270)
			(unlocked yes)
			(layer "F.Fab")
			(hide yes)
			(effects
				(font
					(size 1 1)
					(thickness 0.15)
				)
			)
		)
		(property "License" "Apache-2.0"
			(at 0 0 270)
			(unlocked yes)
			(layer "F.Fab")
			(hide yes)
			(effects
				(font
					(size 1 1)
					(thickness 0.15)
				)
			)
		)
		(property "Author" "Antmicro"
			(at 0 0 270)
			(unlocked yes)
			(layer "F.Fab")
			(hide yes)
			(effects
				(font
					(size 1 1)
					(thickness 0.15)
				)
			)
		)
		(property "Val" "30k"
			(at 0 0 270)
			(unlocked yes)
			(layer "F.Fab")
			(hide yes)
			(effects
				(font
					(size 1 1)
					(thickness 0.15)
				)
			)
		)
		(property "Tolerance" "1%"
			(at 0 0 270)
			(unlocked yes)
			(layer "F.Fab")
			(hide yes)
			(effects
				(font
					(size 1 1)
					(thickness 0.15)
				)
			)
		)
		(sheetname "/Power/")
		(sheetfile "power.kicad_sch")
		(attr smd)
		(fp_rect
			(start -0.925 -0.47)
			(end 0.925 0.47)
			(stroke
				(width 0.05)
				(type default)
			)
			(fill no)
			(layer "F.CrtYd")
		)
		(fp_rect
			(start -0.5 -0.25)
			(end 0.5 0.25)
			(stroke
				(width 0.15)
				(type solid)
			)
			(fill no)
			(layer "F.Fab")
		)
		(pad "1" smd roundrect
			(at -0.48 0 270)
			(size 0.59 0.64)
			(layers "F.Cu" "F.Mask" "F.Paste")
			(roundrect_rratio 0.25)
			(net 28 "GND")
			(pintype "passive")
		)
		(pad "2" smd roundrect
			(at 0.48 0 270)
			(size 0.59 0.64)
			(layers "F.Cu" "F.Mask" "F.Paste")
			(roundrect_rratio 0.25)
			(net 331 "/Power/DVDD_FB")
			(pintype "passive")
		)
	)
	(footprint "antmicro-footprints:C_0603_1608Metric_EIA"
		(layer "F.Cu")
		(at 63.199999 100.850001 180)
		(descr "Capacitor SMD 0603, IPC-7351 Density Level A")
		(tags "Capacitor 0603")
		(property "Reference" "C26"
			(at -2.050001 -0.659999 0)
			(layer "F.SilkS")
			(effects
				(font
					(size 0.7 0.7)
					(thickness 0.15)
				)
				(justify right top)
			)
		)
		(property "Value" "C_22u_16V_0603"
			(at -1.42757 1.770288 0)
			(layer "F.Fab")
			(hide yes)
			(effects
				(font
					(size 0.7 0.7)
					(thickness 0.15)
				)
				(justify right top)
			)
		)
		(property "Datasheet" "https://product.samsungsem.com/mlcc/CL10A226MO7JZN.do"
			(at 0 0 0)
			(layer "F.Fab")
			(hide yes)
			(effects
				(font
					(size 1.27 1.27)
					(thickness 0.15)
				)
			)
		)
		(property "Description" "SMD Multilayer Ceramic Capacitor"
			(at 0 0 0)
			(layer "F.Fab")
			(hide yes)
			(effects
				(font
					(size 1.27 1.27)
					(thickness 0.15)
				)
			)
		)
		(property "MPN" "CL10A226MO7JZNC"
			(at 0 0 180)
			(unlocked yes)
			(layer "F.Fab")
			(hide yes)
			(effects
				(font
					(size 1 1)
					(thickness 0.15)
				)
			)
		)
		(property "Manufacturer" "Samsung Electro-Mechanics"
			(at 0 0 180)
			(unlocked yes)
			(layer "F.Fab")
			(hide yes)
			(effects
				(font
					(size 1 1)
					(thickness 0.15)
				)
			)
		)
		(property "License" "Apache-2.0"
			(at 0 0 180)
			(unlocked yes)
			(layer "F.Fab")
			(hide yes)
			(effects
				(font
					(size 1 1)
					(thickness 0.15)
				)
			)
		)
		(property "Author" "Antmicro"
			(at 0 0 180)
			(unlocked yes)
			(layer "F.Fab")
			(hide yes)
			(effects
				(font
					(size 1 1)
					(thickness 0.15)
				)
			)
		)
		(property "Val" "22u"
			(at 0 0 180)
			(unlocked yes)
			(layer "F.Fab")
			(hide yes)
			(effects
				(font
					(size 1 1)
					(thickness 0.15)
				)
			)
		)
		(property "Voltage" "16V"
			(at 0 0 180)
			(unlocked yes)
			(layer "F.Fab")
			(hide yes)
			(effects
				(font
					(size 1 1)
					(thickness 0.15)
				)
			)
		)
		(property "Dielectric" ""
			(at 0 0 180)
			(unlocked yes)
			(layer "F.Fab")
			(hide yes)
			(effects
				(font
					(size 1 1)
					(thickness 0.15)
				)
			)
		)
		(property "Public" "False"
			(at 0 0 180)
			(unlocked yes)
			(layer "F.Fab")
			(hide yes)
			(effects
				(font
					(size 1 1)
					(thickness 0.15)
				)
			)
		)
		(sheetname "/Power/")
		(sheetfile "power.kicad_sch")
		(attr smd)
		(fp_line
			(start -0.15 0.55)
			(end 0.15 0.55)
			(stroke
				(width 0.15)
				(type solid)
			)
			(layer "F.SilkS")
		)
		(fp_line
			(start -0.15 -0.55)
			(end 0.15 -0.55)
			(stroke
				(width 0.15)
				(type solid)
			)
			(layer "F.SilkS")
		)
		(fp_rect
			(start -1.25 -0.65)
			(end 1.25 0.65)
			(stroke
				(width 0.05)
				(type solid)
			)
			(fill no)
			(layer "F.CrtYd")
		)
		(fp_rect
			(start -0.8 -0.45)
			(end 0.8 0.45)
			(stroke
				(width 0.15)
				(type solid)
			)
			(fill no)
			(layer "F.Fab")
		)
		(pad "1" smd roundrect
			(at -0.7 0 180)
			(size 0.8 1.1)
			(layers "F.Cu" "F.Mask" "F.Paste")
			(roundrect_rratio 0.2)
			(net 28 "GND")
			(pintype "passive")
		)
		(pad "2" smd roundrect
			(at 0.7 0 180)
			(size 0.8 1.1)
			(layers "F.Cu" "F.Mask" "F.Paste")
			(roundrect_rratio 0.2)
			(net 310 "/Power/+1V88_OUT")
			(pintype "passive")
		)
	)
	(footprint "antmicro-footprints:C_0603_1608Metric_EIA"
		(layer "F.Cu")
		(at 63.199998 93.15 180)
		(descr "Capacitor SMD 0603, IPC-7351 Density Level A")
		(tags "Capacitor 0603")
		(property "Reference" "C208"
			(at -2.610002 -0.73 0)
			(layer "F.SilkS")
			(effects
				(font
					(size 0.7 0.7)
					(thickness 0.15)
				)
				(justify right top)
			)
		)
		(property "Value" "C_22u_16V_0603"
			(at -1.42757 1.770288 0)
			(layer "F.Fab")
			(hide yes)
			(effects
				(font
					(size 0.7 0.7)
					(thickness 0.15)
				)
				(justify right top)
			)
		)
		(property "Datasheet" "https://product.samsungsem.com/mlcc/CL10A226MO7JZN.do"
			(at 0 0 0)
			(layer "F.Fab")
			(hide yes)
			(effects
				(font
					(size 1.27 1.27)
					(thickness 0.15)
				)
			)
		)
		(property "Description" "SMD Multilayer Ceramic Capacitor"
			(at 0 0 0)
			(layer "F.Fab")
			(hide yes)
			(effects
				(font
					(size 1.27 1.27)
					(thickness 0.15)
				)
			)
		)
		(property "MPN" "CL10A226MO7JZNC"
			(at 0 0 180)
			(unlocked yes)
			(layer "F.Fab")
			(hide yes)
			(effects
				(font
					(size 1 1)
					(thickness 0.15)
				)
			)
		)
		(property "Manufacturer" "Samsung Electro-Mechanics"
			(at 0 0 180)
			(unlocked yes)
			(layer "F.Fab")
			(hide yes)
			(effects
				(font
					(size 1 1)
					(thickness 0.15)
				)
			)
		)
		(property "License" "Apache-2.0"
			(at 0 0 180)
			(unlocked yes)
			(layer "F.Fab")
			(hide yes)
			(effects
				(font
					(size 1 1)
					(thickness 0.15)
				)
			)
		)
		(property "Author" "Antmicro"
			(at 0 0 180)
			(unlocked yes)
			(layer "F.Fab")
			(hide yes)
			(effects
				(font
					(size 1 1)
					(thickness 0.15)
				)
			)
		)
		(property "Val" "22u"
			(at 0 0 180)
			(unlocked yes)
			(layer "F.Fab")
			(hide yes)
			(effects
				(font
					(size 1 1)
					(thickness 0.15)
				)
			)
		)
		(property "Voltage" "16V"
			(at 0 0 180)
			(unlocked yes)
			(layer "F.Fab")
			(hide yes)
			(effects
				(font
					(size 1 1)
					(thickness 0.15)
				)
			)
		)
		(property "Dielectric" ""
			(at 0 0 180)
			(unlocked yes)
			(layer "F.Fab")
			(hide yes)
			(effects
				(font
					(size 1 1)
					(thickness 0.15)
				)
			)
		)
		(property "Public" "False"
			(at 0 0 180)
			(unlocked yes)
			(layer "F.Fab")
			(hide yes)
			(effects
				(font
					(size 1 1)
					(thickness 0.15)
				)
			)
		)
		(sheetname "/Power/")
		(sheetfile "power.kicad_sch")
		(attr smd)
		(fp_line
			(start -0.15 0.55)
			(end 0.15 0.55)
			(stroke
				(width 0.15)
				(type solid)
			)
			(layer "F.SilkS")
		)
		(fp_line
			(start -0.15 -0.55)
			(end 0.15 -0.55)
			(stroke
				(width 0.15)
				(type solid)
			)
			(layer "F.SilkS")
		)
		(fp_rect
			(start -1.25 -0.65)
			(end 1.25 0.65)
			(stroke
				(width 0.05)
				(type solid)
			)
			(fill no)
			(layer "F.CrtYd")
		)
		(fp_rect
			(start -0.8 -0.45)
			(end 0.8 0.45)
			(stroke
				(width 0.15)
				(type solid)
			)
			(fill no)
			(layer "F.Fab")
		)
		(pad "1" smd roundrect
			(at -0.7 0 180)
			(size 0.8 1.1)
			(layers "F.Cu" "F.Mask" "F.Paste")
			(roundrect_rratio 0.2)
			(net 28 "GND")
			(pintype "passive")
		)
		(pad "2" smd roundrect
			(at 0.7 0 180)
			(size 0.8 1.1)
			(layers "F.Cu" "F.Mask" "F.Paste")
			(roundrect_rratio 0.2)
			(net 311 "/Power/+DVDD_OUT")
			(pintype "passive")
		)
	)
	(footprint "antmicro-footprints:USB-C_Receptacle_GCT_USB4105-GF-A"
		(layer "F.Cu")
		(at 82.9 52.704 180)
		(property "Reference" "J2"
			(at -5.24 -2.328 90)
			(layer "F.SilkS")
			(effects
				(font
					(size 0.7 0.7)
					(thickness 0.15)
				)
				(justify right top)
			)
		)
		(property "Value" "USB-C_GCT_USB4105-GF-A"
			(at 0 5 0)
			(layer "F.Fab")
			(hide yes)
			(effects
				(font
					(size 0.7 0.7)
					(thickness 0.15)
				)
				(justify right top)
			)
		)
		(property "Datasheet" "https://gct.co/files/drawings/usb4105.pdf"
			(at 0 0 0)
			(layer "F.Fab")
			(hide yes)
			(effects
				(font
					(size 1.27 1.27)
					(thickness 0.15)
				)
			)
		)
		(property "Description" "USB-C (USB TYPE-C) USB 2.0 Receptacle Connector 24 (16+8 Dummy) Position Surface Mount, Right Angle"
			(at 0 0 0)
			(layer "F.Fab")
			(hide yes)
			(effects
				(font
					(size 1.27 1.27)
					(thickness 0.15)
				)
			)
		)
		(property "Manufacturer" "GCT"
			(at 0 0 180)
			(unlocked yes)
			(layer "F.Fab")
			(hide yes)
			(effects
				(font
					(size 1 1)
					(thickness 0.15)
				)
			)
		)
		(property "MPN" "USB4105-GF-A"
			(at 0 0 180)
			(unlocked yes)
			(layer "F.Fab")
			(hide yes)
			(effects
				(font
					(size 1 1)
					(thickness 0.15)
				)
			)
		)
		(property "Author" "Antmicro"
			(at 0 0 180)
			(unlocked yes)
			(layer "F.Fab")
			(hide yes)
			(effects
				(font
					(size 1 1)
					(thickness 0.15)
				)
			)
		)
		(property "License" "Apache-2.0"
			(at 0 0 180)
			(unlocked yes)
			(layer "F.Fab")
			(hide yes)
			(effects
				(font
					(size 1 1)
					(thickness 0.15)
				)
			)
		)
		(sheetname "/Power/")
		(sheetfile "power.kicad_sch")
		(attr smd)
		(fp_line
			(start 4.788 3.854)
			(end 4.788 2.575)
			(stroke
				(width 0.15)
				(type solid)
			)
			(layer "F.SilkS")
		)
		(fp_line
			(start 4.788 -1.395)
			(end 4.788 -0.145)
			(stroke
				(width 0.15)
				(type solid)
			)
			(layer "F.SilkS")
		)
		(fp_line
			(start -4.79 3.854)
			(end 4.788 3.854)
			(stroke
				(width 0.15)
				(type solid)
			)
			(layer "F.SilkS")
		)
		(fp_line
			(start -4.79 2.575)
			(end -4.79 3.854)
			(stroke
				(width 0.15)
				(type solid)
			)
			(layer "F.SilkS")
		)
		(fp_line
			(start -4.79 -1.395)
			(end -4.79 -0.145)
			(stroke
				(width 0.15)
				(type solid)
			)
			(layer "F.SilkS")
		)
		(fp_circle
			(center -3.8 -4.27071)
			(end -3.75 -4.22071)
			(stroke
				(width 0.15)
				(type solid)
			)
			(fill yes)
			(layer "F.SilkS")
		)
		(fp_rect
			(start -5.1 -4.4)
			(end 5.1 3.9)
			(stroke
				(width 0.05)
				(type solid)
			)
			(fill no)
			(layer "F.CrtYd")
		)
		(fp_line
			(start 4.788 3.854)
			(end -4.79 3.854)
			(stroke
				(width 0.15)
				(type solid)
			)
			(layer "F.Fab")
		)
		(fp_line
			(start 4.788 -3.676)
			(end 4.788 3.854)
			(stroke
				(width 0.15)
				(type solid)
			)
			(layer "F.Fab")
		)
		(fp_line
			(start -4.702 3.854)
			(end 4.788 3.854)
			(stroke
				(width 0.15)
				(type solid)
			)
			(layer "F.Fab")
		)
		(fp_line
			(start -4.79 3.854)
			(end -4.79 -3.676)
			(stroke
				(width 0.15)
				(type solid)
			)
			(layer "F.Fab")
		)
		(fp_line
			(start -4.79 -3.676)
			(end 4.788 -3.676)
			(stroke
				(width 0.15)
				(type solid)
			)
			(layer "F.Fab")
		)
		(pad "" np_thru_hole circle
			(at -2.891 -2.426 180)
			(size 0.65 0.65)
			(drill 0.65)
			(layers "*.Cu" "*.Mask")
		)
		(pad "" np_thru_hole circle
			(at 2.89 -2.426 180)
			(size 0.65 0.65)
			(drill 0.65)
			(layers "*.Cu" "*.Mask")
		)
		(pad "A1" smd roundrect
			(at -3.202 -3.5 180)
			(size 0.6 1.15)
			(layers "F.Cu" "F.Mask" "F.Paste")
			(roundrect_rratio 0.25)
			(net 28 "GND")
			(pinfunction "GND")
			(pintype "power_in")
		)
		(pad "A4" smd roundrect
			(at -2.4 -3.5 180)
			(size 0.6 1.15)
			(layers "F.Cu" "F.Mask" "F.Paste")
			(roundrect_rratio 0.25)
			(net 351 "/Power/+5V_USB")
			(pinfunction "VBUS")
			(pintype "power_in")
		)
		(pad "A5" smd roundrect
			(at -1.25 -3.5 180)
			(size 0.3 1.15)
			(layers "F.Cu" "F.Mask" "F.Paste")
			(roundrect_rratio 0.25)
			(net 357 "/Power/CC1")
			(pinfunction "CC_{1}")
			(pintype "bidirectional")
		)
		(pad "A6" smd roundrect
			(at -0.25 -3.5 180)
			(size 0.3 1.15)
			(layers "F.Cu" "F.Mask" "F.Paste")
			(roundrect_rratio 0.25)
			(net 146 "unconnected-(J2-D_{A}+-PadA6)")
			(pinfunction "D_{A}+")
			(pintype "bidirectional+no_connect")
		)
		(pad "A7" smd roundrect
			(at 0.248 -3.5 180)
			(size 0.3 1.15)
			(layers "F.Cu" "F.Mask" "F.Paste")
			(roundrect_rratio 0.25)
			(net 144 "unconnected-(J2-D_{A}--PadA7)")
			(pinfunction "D_{A}-")
			(pintype "bidirectional+no_connect")
		)
		(pad "A8" smd roundrect
			(at 1.249 -3.5 180)
			(size 0.3 1.15)
			(layers "F.Cu" "F.Mask" "F.Paste")
			(roundrect_rratio 0.25)
			(net 93 "unconnected-(J2-SBU_{1}-PadA8)")
			(pinfunction "SBU_{1}")
			(pintype "bidirectional+no_connect")
		)
		(pad "A9" smd roundrect
			(at 2.398 -3.5 180)
			(size 0.6 1.15)
			(layers "F.Cu" "F.Mask" "F.Paste")
			(roundrect_rratio 0.25)
			(net 351 "/Power/+5V_USB")
			(pinfunction "VBUS")
			(pintype "passive")
		)
		(pad "A12" smd roundrect
			(at 3.2 -3.5 180)
			(size 0.6 1.15)
			(layers "F.Cu" "F.Mask" "F.Paste")
			(roundrect_rratio 0.25)
			(net 28 "GND")
			(pinfunction "GND")
			(pintype "passive")
		)
		(pad "B1" smd roundrect
			(at 3.2 -3.5 180)
			(size 0.6 1.15)
			(layers "F.Cu" "F.Mask" "F.Paste")
			(roundrect_rratio 0.25)
			(net 28 "GND")
			(pinfunction "GND")
			(pintype "passive")
		)
		(pad "B4" smd roundrect
			(at 2.398 -3.5 180)
			(size 0.6 1.15)
			(layers "F.Cu" "F.Mask" "F.Paste")
			(roundrect_rratio 0.25)
			(net 351 "/Power/+5V_USB")
			(pinfunction "VBUS")
			(pintype "passive")
		)
		(pad "B5" smd roundrect
			(at 1.749 -3.5 180)
			(size 0.3 1.15)
			(layers "F.Cu" "F.Mask" "F.Paste")
			(roundrect_rratio 0.25)
			(net 356 "/Power/CC2")
			(pinfunction "CC_{2}")
			(pintype "bidirectional")
		)
		(pad "B6" smd roundrect
			(at 0.748 -3.5 180)
			(size 0.3 1.15)
			(layers "F.Cu" "F.Mask" "F.Paste")
			(roundrect_rratio 0.25)
			(net 138 "unconnected-(J2-D_{B}+-PadB6)")
			(pinfunction "D_{B}+")
			(pintype "bidirectional+no_connect")
		)
		(pad "B7" smd roundrect
			(at -0.75 -3.5 180)
			(size 0.3 1.15)
			(layers "F.Cu" "F.Mask" "F.Paste")
			(roundrect_rratio 0.25)
			(net 92 "unconnected-(J2-D_{B}--PadB7)")
			(pinfunction "D_{B}-")
			(pintype "bidirectional+no_connect")
		)
		(pad "B8" smd roundrect
			(at -1.75 -3.5 180)
			(size 0.3 1.15)
			(layers "F.Cu" "F.Mask" "F.Paste")
			(roundrect_rratio 0.25)
			(net 145 "unconnected-(J2-SBU_{2}-PadB8)")
			(pinfunction "SBU_{2}")
			(pintype "bidirectional+no_connect")
		)
		(pad "B9" smd roundrect
			(at -2.4 -3.5 180)
			(size 0.6 1.15)
			(layers "F.Cu" "F.Mask" "F.Paste")
			(roundrect_rratio 0.25)
			(net 351 "/Power/+5V_USB")
			(pinfunction "VBUS")
			(pintype "passive")
		)
		(pad "B12" smd roundrect
			(at -3.202 -3.5 180)
			(size 0.6 1.15)
			(layers "F.Cu" "F.Mask" "F.Paste")
			(roundrect_rratio 0.25)
			(net 28 "GND")
			(pinfunction "GND")
			(pintype "passive")
		)
		(pad "SH" thru_hole oval
			(at -4.321 -2.926 180)
			(size 1.05 2.1)
			(drill oval 0.6 1.7)
			(layers "*.Cu" "*.Mask")
			(remove_unused_layers no)
			(net 43 "Net-(C37-Pad2)")
			(pinfunction "SH")
			(pintype "passive")
		)
		(pad "SH" thru_hole oval
			(at -4.321 1.255 180)
			(size 1 2)
			(drill oval 0.6 1.4)
			(layers "*.Cu" "*.Mask")
			(remove_unused_layers no)
			(net 43 "Net-(C37-Pad2)")
			(pinfunction "SH")
			(pintype "passive")
		)
		(pad "SH" thru_hole oval
			(at 4.32 -2.926 180)
			(size 1.05 2.1)
			(drill oval 0.6 1.7)
			(layers "*.Cu" "*.Mask")
			(remove_unused_layers no)
			(net 43 "Net-(C37-Pad2)")
			(pinfunction "SH")
			(pintype "passive")
		)
		(pad "SH" thru_hole oval
			(at 4.32 1.255 180)
			(size 1 2)
			(drill oval 0.6 1.4)
			(layers "*.Cu" "*.Mask")
			(remove_unused_layers no)
			(net 43 "Net-(C37-Pad2)")
			(pinfunction "SH")
			(pintype "passive")
		)
	)
)
